# S9S_MB_2U (Grand Teton) — schematic netlist excerpt (pin names and nets, part order shuffled) for the footprints in the layout excerpt that follows; sources: Cadence DE-HDL packaged netlist, KiCad conversion of 03242023_DA0F0TMBIJ0_F0T_Motherboard_J_brd_V01_OCP.brd

R3164  Q_RES  10K 1% CHIP  pkg 0402LF  page 159 : A = GND ; B = OCP_V3_2_AUX_PWR_EN
R2114  Q_RES  0 5% CHIP  pkg 0402LF  page 191 : A = SMB_PCIE_E1S_ISO_EN_R2 ; B = SMB_PCIE_E1S_ISO_EN

(kicad_pcb
	(version 20260206)
	(generator "pcbnew")
	(generator_version "10.0")
	(general
		(thickness 1.6)
		(legacy_teardrops no)
	)
	(paper "A4")
	(title_block
		(title "03242023_DA0F0TMBIJ0_F0T_Motherboard_J_brd_V01_OCP.brd")
		(comment 1 "Grand Teton / footprints 1445-1446 of 6105")
	)
	(layers
		(0 "F.Cu" signal "TOP")
		(4 "In1.Cu" signal "GND")
		(6 "In2.Cu" signal "IN1")
		(8 "In3.Cu" signal "GND1")
		(10 "In4.Cu" signal "IN2")
		(12 "In5.Cu" signal "GND2")
		(14 "In6.Cu" signal "IN3")
		(16 "In7.Cu" signal "GND3")
		(18 "In8.Cu" signal "VCC")
		(20 "In9.Cu" signal "VCC1")
		(22 "In10.Cu" signal "GND4")
		(24 "In11.Cu" signal "IN4")
		(26 "In12.Cu" signal "GND5")
		(28 "In13.Cu" signal "IN5")
		(30 "In14.Cu" signal "GND6")
		(32 "In15.Cu" signal "IN6")
		(34 "In16.Cu" signal "GND7")
		(2 "B.Cu" signal "BOTTOM")
		(9 "F.Adhes" user "F.Adhesive")
		(11 "B.Adhes" user "B.Adhesive")
		(13 "F.Paste" user "Package Geometry/Pastemask Top")
		(15 "B.Paste" user "Package Geometry/Pastemask Bottom")
		(5 "F.SilkS" user "Ref Des/Silkscreen Top")
		(7 "B.SilkS" user "Ref Des/Silkscreen Bottom")
		(1 "F.Mask" user "Board Geometry/Soldermask Top")
		(3 "B.Mask" user "Board Geometry/Soldermask Bottom")
		(17 "Dwgs.User" user "User.Drawings")
		(19 "Cmts.User" user "User.Comments")
		(21 "Eco1.User" user "User.Eco1")
		(23 "Eco2.User" user "User.Eco2")
		(25 "Edge.Cuts" user "Board Geometry/Outline")
		(27 "Margin" user)
		(31 "F.CrtYd" user "Package Geometry/Place Bound Top")
		(29 "B.CrtYd" user "Package Geometry/Place Bound Bottom")
		(35 "F.Fab" user "Ref Des/Assembly Top")
		(33 "B.Fab" user "Ref Des/Assembly Bottom")
	)
	(footprint ""
		(layer "F.Cu")
		(at 61.90488 -19.268948 180)
		(property "Reference" "R3164"
			(at 0 0 180)
			(layer "F.SilkS")
			(hide yes)
			(effects
				(font
					(size 1.27 1.27)
				)
			)
		)
		(property "Value" ""
			(at 0 0 180)
			(layer "F.Fab")
			(effects
				(font
					(size 1.27 1.27)
				)
			)
		)
		(duplicate_pad_numbers_are_jumpers no)
		(fp_line
			(start 0.7874 0.4064)
			(end -0.7874 0.4064)
			(stroke
				(width 0.1524)
				(type default)
			)
			(layer "F.SilkS")
		)
		(fp_line
			(start 0.7874 -0.4064)
			(end 0.7874 0.4064)
			(stroke
				(width 0.1524)
				(type default)
			)
			(layer "F.SilkS")
		)
		(fp_line
			(start -0.7874 0.4064)
			(end -0.7874 -0.4064)
			(stroke
				(width 0.1524)
				(type default)
			)
			(layer "F.SilkS")
		)
		(fp_line
			(start -0.7874 -0.4064)
			(end 0.7874 -0.4064)
			(stroke
				(width 0.1524)
				(type default)
			)
			(layer "F.SilkS")
		)
		(fp_line
			(start 0.67945 0.3048)
			(end 0.120396 0.3048)
			(stroke
				(width 0.1)
				(type default)
			)
			(layer "F.Fab")
		)
		(fp_line
			(start 0.67945 -0.3048)
			(end 0.67945 0.3048)
			(stroke
				(width 0.1)
				(type default)
			)
			(layer "F.Fab")
		)
		(fp_line
			(start 0.12065 -0.2794)
			(end 0.12065 -0.3048)
			(stroke
				(width 0.1)
				(type default)
			)
			(layer "F.Fab")
		)
		(fp_line
			(start 0.12065 -0.3048)
			(end 0.67945 -0.3048)
			(stroke
				(width 0.1)
				(type default)
			)
			(layer "F.Fab")
		)
		(fp_line
			(start 0.120396 0.3048)
			(end 0.120396 0.2794)
			(stroke
				(width 0.1)
				(type default)
			)
			(layer "F.Fab")
		)
		(fp_line
			(start 0.120396 0.2794)
			(end -0.12065 0.2794)
			(stroke
				(width 0.1)
				(type default)
			)
			(layer "F.Fab")
		)
		(fp_line
			(start -0.12065 0.3048)
			(end -0.67945 0.3048)
			(stroke
				(width 0.1)
				(type default)
			)
			(layer "F.Fab")
		)
		(fp_line
			(start -0.12065 0.2794)
			(end -0.12065 0.3048)
			(stroke
				(width 0.1)
				(type default)
			)
			(layer "F.Fab")
		)
		(fp_line
			(start -0.12065 -0.2794)
			(end 0.12065 -0.2794)
			(stroke
				(width 0.1)
				(type default)
			)
			(layer "F.Fab")
		)
		(fp_line
			(start -0.12065 -0.305054)
			(end -0.12065 -0.2794)
			(stroke
				(width 0.1)
				(type default)
			)
			(layer "F.Fab")
		)
		(fp_line
			(start -0.67945 0.3048)
			(end -0.67945 -0.305054)
			(stroke
				(width 0.1)
				(type default)
			)
			(layer "F.Fab")
		)
		(fp_line
			(start -0.67945 -0.305054)
			(end -0.12065 -0.305054)
			(stroke
				(width 0.1)
				(type default)
			)
			(layer "F.Fab")
		)
		(pad "1" smd circle
			(at -0.40005 0 180)
			(size 0 0)
			(layers "F.Cu" "F.Mask" "F.Paste")
			(net "GND")
		)
		(pad "2" smd circle
			(at 0.40005 0 180)
			(size 0 0)
			(layers "F.Cu" "F.Mask" "F.Paste")
			(net "OCP_V3_2_AUX_PWR_EN")
		)
	)
	(footprint ""
		(layer "F.Cu")
		(at 159.655256 -63.297308)
		(property "Reference" "R2114"
			(at 0 0 0)
			(layer "F.SilkS")
			(hide yes)
			(effects
				(font
					(size 1.27 1.27)
				)
			)
		)
		(property "Value" ""
			(at 0 0 0)
			(layer "F.Fab")
			(effects
				(font
					(size 1.27 1.27)
				)
			)
		)
		(duplicate_pad_numbers_are_jumpers no)
		(fp_line
			(start -0.7874 -0.4064)
			(end 0.7874 -0.4064)
			(stroke
				(width 0.1524)
				(type default)
			)
			(layer "F.SilkS")
		)
		(fp_line
			(start -0.7874 0.4064)
			(end -0.7874 -0.4064)
			(stroke
				(width 0.1524)
				(type default)
			)
			(layer "F.SilkS")
		)
		(fp_line
			(start 0.7874 -0.4064)
			(end 0.7874 0.4064)
			(stroke
				(width 0.1524)
				(type default)
			)
			(layer "F.SilkS")
		)
		(fp_line
			(start 0.7874 0.4064)
			(end -0.7874 0.4064)
			(stroke
				(width 0.1524)
				(type default)
			)
			(layer "F.SilkS")
		)
		(fp_line
			(start -0.67945 -0.305054)
			(end -0.12065 -0.305054)
			(stroke
				(width 0.1)
				(type default)
			)
			(layer "F.Fab")
		)
		(fp_line
			(start -0.67945 0.3048)
			(end -0.67945 -0.305054)
			(stroke
				(width 0.1)
				(type default)
			)
			(layer "F.Fab")
		)
		(fp_line
			(start -0.12065 -0.305054)
			(end -0.12065 -0.2794)
			(stroke
				(width 0.1)
				(type default)
			)
			(layer "F.Fab")
		)
		(fp_line
			(start -0.12065 -0.2794)
			(end 0.12065 -0.2794)
			(stroke
				(width 0.1)
				(type default)
			)
			(layer "F.Fab")
		)
		(fp_line
			(start -0.12065 0.2794)
			(end -0.12065 0.3048)
			(stroke
				(width 0.1)
				(type default)
			)
			(layer "F.Fab")
		)
		(fp_line
			(start -0.12065 0.3048)
			(end -0.67945 0.3048)
			(stroke
				(width 0.1)
				(type default)
			)
			(layer "F.Fab")
		)
		(fp_line
			(start 0.120396 0.2794)
			(end -0.12065 0.2794)
			(stroke
				(width 0.1)
				(type default)
			)
			(layer "F.Fab")
		)
		(fp_line
			(start 0.120396 0.3048)
			(end 0.120396 0.2794)
			(stroke
				(width 0.1)
				(type default)
			)
			(layer "F.Fab")
		)
		(fp_line
			(start 0.12065 -0.3048)
			(end 0.67945 -0.3048)
			(stroke
				(width 0.1)
				(type default)
			)
			(layer "F.Fab")
		)
		(fp_line
			(start 0.12065 -0.2794)
			(end 0.12065 -0.3048)
			(stroke
				(width 0.1)
				(type default)
			)
			(layer "F.Fab")
		)
		(fp_line
			(start 0.67945 -0.3048)
			(end 0.67945 0.3048)
			(stroke
				(width 0.1)
				(type default)
			)
			(layer "F.Fab")
		)
		(fp_line
			(start 0.67945 0.3048)
			(end 0.120396 0.3048)
			(stroke
				(width 0.1)
				(type default)
			)
			(layer "F.Fab")
		)
		(pad "1" smd circle
			(at -0.40005 0)
			(size 0 0)
			(layers "F.Cu" "F.Mask" "F.Paste")
			(net "SMB_PCIE_E1S_ISO_EN_R2")
		)
		(pad "2" smd circle
			(at 0.40005 0)
			(size 0 0)
			(layers "F.Cu" "F.Mask" "F.Paste")
			(net "SMB_PCIE_E1S_ISO_EN")
		)
	)
)
